# T6G (Grand Teton) — schematic netlist excerpt (pin names and nets, part order shuffled) for the footprints in the layout excerpt that follows; sources: Cadence DE-HDL packaged netlist, KiCad conversion of 04192023_DAF0TMB3IC0_F0TG_MB_C_brd_V02_OCP.brd

J6  CONN6_HBC1031L200D8H  CONN6_HBC1031-L200D-8H IO  pkg HEADER2X3XE  page 28
  \1\  = CPU0_PWR_BTN_N
  \2\  = GND
  \3\  = RST_CPU0_SYS_N
  \4\  = GND
  \5\  = NC
  \6\  = GND

R3653  Q_RES  680 1% CHIP  pkg 0402LF  page 234 : A = USB_HUB_RREF ; B = GND

(kicad_pcb
	(version 20260206)
	(generator "pcbnew")
	(generator_version "10.0")
	(general
		(thickness 1.6)
		(legacy_teardrops no)
	)
	(paper "A4")
	(title_block
		(title "04192023_DAF0TMB3IC0_F0TG_MB_C_brd_V02_OCP.brd")
		(comment 1 "Grand Teton / footprints 2937-2938 of 8354")
	)
	(layers
		(0 "F.Cu" signal "TOP")
		(4 "In1.Cu" signal "GND")
		(6 "In2.Cu" signal "IN1")
		(8 "In3.Cu" signal "GND1")
		(10 "In4.Cu" signal "IN2")
		(12 "In5.Cu" signal "GND2")
		(14 "In6.Cu" signal "IN3")
		(16 "In7.Cu" signal "GND3")
		(18 "In8.Cu" signal "VCC")
		(20 "In9.Cu" signal "VCC1")
		(22 "In10.Cu" signal "GND4")
		(24 "In11.Cu" signal "IN4")
		(26 "In12.Cu" signal "GND5")
		(28 "In13.Cu" signal "IN5")
		(30 "In14.Cu" signal "GND6")
		(32 "In15.Cu" signal "IN6")
		(34 "In16.Cu" signal "GND7")
		(2 "B.Cu" signal "BOTTOM")
		(9 "F.Adhes" user "F.Adhesive")
		(11 "B.Adhes" user "B.Adhesive")
		(13 "F.Paste" user "Package Geometry/Pastemask Top")
		(15 "B.Paste" user "Package Geometry/Pastemask Bottom")
		(5 "F.SilkS" user "Ref Des/Silkscreen Top")
		(7 "B.SilkS" user "Ref Des/Silkscreen Bottom")
		(1 "F.Mask" user "Board Geometry/Soldermask Top")
		(3 "B.Mask" user "Board Geometry/Soldermask Bottom")
		(17 "Dwgs.User" user "User.Drawings")
		(19 "Cmts.User" user "User.Comments")
		(21 "Eco1.User" user "User.Eco1")
		(23 "Eco2.User" user "User.Eco2")
		(25 "Edge.Cuts" user "Board Geometry/Outline")
		(27 "Margin" user)
		(31 "F.CrtYd" user "Package Geometry/Place Bound Top")
		(29 "B.CrtYd" user "Package Geometry/Place Bound Bottom")
		(35 "F.Fab" user "Ref Des/Assembly Top")
		(33 "B.Fab" user "Ref Des/Assembly Bottom")
	)
	(footprint ""
		(layer "F.Cu")
		(at 298.159932 -52.63007 90)
		(property "Reference" "J6"
			(at -1.948434 2.597658 0)
			(unlocked yes)
			(layer "F.SilkS")
			(effects
				(font
					(size 0.7874 0.5842)
					(thickness 0.1524)
				)
			)
		)
		(property "Value" ""
			(at 0 0 90)
			(layer "F.Fab")
			(effects
				(font
					(size 1.27 1.27)
				)
			)
		)
		(duplicate_pad_numbers_are_jumpers no)
		(fp_line
			(start 3.759962 -1.335024)
			(end 3.759962 6.415024)
			(stroke
				(width 0.1524)
				(type default)
			)
			(layer "F.SilkS")
		)
		(fp_line
			(start -1.219962 -1.335024)
			(end 3.759962 -1.335024)
			(stroke
				(width 0.1524)
				(type default)
			)
			(layer "F.SilkS")
		)
		(fp_line
			(start 3.759962 6.415024)
			(end -1.219962 6.415024)
			(stroke
				(width 0.1524)
				(type default)
			)
			(layer "F.SilkS")
		)
		(fp_line
			(start -1.219962 6.415024)
			(end -1.219962 -1.335024)
			(stroke
				(width 0.1524)
				(type default)
			)
			(layer "F.SilkS")
		)
		(fp_poly
			(pts
				(xy -1.423162 0) (xy -2.439162 0.508) (xy -2.439162 -0.508)
			)
			(stroke
				(width 0)
				(type default)
			)
			(fill yes)
			(layer "F.SilkS")
		)
		(fp_line
			(start 3.759962 -1.335024)
			(end 3.759962 6.415024)
			(stroke
				(width 0.1)
				(type default)
			)
			(layer "F.Fab")
		)
		(fp_line
			(start -1.219962 -1.335024)
			(end 3.759962 -1.335024)
			(stroke
				(width 0.1)
				(type default)
			)
			(layer "F.Fab")
		)
		(fp_line
			(start 3.759962 6.415024)
			(end -1.219962 6.415024)
			(stroke
				(width 0.1)
				(type default)
			)
			(layer "F.Fab")
		)
		(fp_line
			(start -1.219962 6.415024)
			(end -1.219962 -1.335024)
			(stroke
				(width 0.1)
				(type default)
			)
			(layer "F.Fab")
		)
		(fp_poly
			(pts
				(xy -2.439162 -0.508) (xy -2.439162 0.508) (xy -1.423162 0)
			)
			(stroke
				(width 0)
				(type default)
			)
			(fill yes)
			(layer "F.Fab")
		)
		(pad "1" thru_hole rect
			(at 0 0 90)
			(size 1.6256 1.6256)
			(drill 1.1176)
			(layers "*.Cu" "*.Mask")
			(remove_unused_layers no)
			(net "CPU0_PWR_BTN_N")
			(clearance 0)
			(padstack
				(mode front_inner_back)
				(layer "Inner"
					(shape circle)
					(size 1.6256 1.6256)
					(clearance 0)
				)
				(layer "B.Cu"
					(shape rect)
					(size 1.6256 1.6256)
					(clearance 0)
				)
			)
		)
		(pad "2" thru_hole circle
			(at 2.54 0 90)
			(size 1.6256 1.6256)
			(drill 1.1176)
			(layers "*.Cu" "*.Mask")
			(remove_unused_layers no)
			(net "GND")
			(clearance 0)
		)
		(pad "3" thru_hole circle
			(at 0 2.54 90)
			(size 1.6256 1.6256)
			(drill 1.1176)
			(layers "*.Cu" "*.Mask")
			(remove_unused_layers no)
			(net "RST_CPU0_SYS_N")
			(clearance 0)
		)
		(pad "4" thru_hole circle
			(at 2.54 2.54 90)
			(size 1.6256 1.6256)
			(drill 1.1176)
			(layers "*.Cu" "*.Mask")
			(remove_unused_layers no)
			(net "GND")
			(clearance 0)
		)
		(pad "5" thru_hole circle
			(at 0 5.08 90)
			(size 1.6256 1.6256)
			(drill 1.1176)
			(layers "*.Cu" "*.Mask")
			(remove_unused_layers no)
			(net "Net_10748")
			(clearance 0)
		)
		(pad "6" thru_hole circle
			(at 2.54 5.08 90)
			(size 1.6256 1.6256)
			(drill 1.1176)
			(layers "*.Cu" "*.Mask")
			(remove_unused_layers no)
			(net "GND")
			(clearance 0)
		)
	)
	(footprint ""
		(layer "F.Cu")
		(at 8.75919 -101.854 180)
		(property "Reference" "R3653"
			(at 0 0 180)
			(layer "F.SilkS")
			(hide yes)
			(effects
				(font
					(size 1.27 1.27)
				)
			)
		)
		(property "Value" ""
			(at 0 0 180)
			(layer "F.Fab")
			(effects
				(font
					(size 1.27 1.27)
				)
			)
		)
		(duplicate_pad_numbers_are_jumpers no)
		(fp_line
			(start 0.7874 0.4064)
			(end -0.7874 0.4064)
			(stroke
				(width 0.1524)
				(type default)
			)
			(layer "F.SilkS")
		)
		(fp_line
			(start 0.7874 -0.4064)
			(end 0.7874 0.4064)
			(stroke
				(width 0.1524)
				(type default)
			)
			(layer "F.SilkS")
		)
		(fp_line
			(start -0.7874 0.4064)
			(end -0.7874 -0.4064)
			(stroke
				(width 0.1524)
				(type default)
			)
			(layer "F.SilkS")
		)
		(fp_line
			(start -0.7874 -0.4064)
			(end 0.7874 -0.4064)
			(stroke
				(width 0.1524)
				(type default)
			)
			(layer "F.SilkS")
		)
		(fp_line
			(start 0.67945 0.3048)
			(end 0.120396 0.3048)
			(stroke
				(width 0.1)
				(type default)
			)
			(layer "F.Fab")
		)
		(fp_line
			(start 0.67945 -0.3048)
			(end 0.67945 0.3048)
			(stroke
				(width 0.1)
				(type default)
			)
			(layer "F.Fab")
		)
		(fp_line
			(start 0.12065 -0.2794)
			(end 0.12065 -0.3048)
			(stroke
				(width 0.1)
				(type default)
			)
			(layer "F.Fab")
		)
		(fp_line
			(start 0.12065 -0.3048)
			(end 0.67945 -0.3048)
			(stroke
				(width 0.1)
				(type default)
			)
			(layer "F.Fab")
		)
		(fp_line
			(start 0.120396 0.3048)
			(end 0.120396 0.2794)
			(stroke
				(width 0.1)
				(type default)
			)
			(layer "F.Fab")
		)
		(fp_line
			(start 0.120396 0.2794)
			(end -0.12065 0.2794)
			(stroke
				(width 0.1)
				(type default)
			)
			(layer "F.Fab")
		)
		(fp_line
			(start -0.12065 0.3048)
			(end -0.67945 0.3048)
			(stroke
				(width 0.1)
				(type default)
			)
			(layer "F.Fab")
		)
		(fp_line
			(start -0.12065 0.2794)
			(end -0.12065 0.3048)
			(stroke
				(width 0.1)
				(type default)
			)
			(layer "F.Fab")
		)
		(fp_line
			(start -0.12065 -0.2794)
			(end 0.12065 -0.2794)
			(stroke
				(width 0.1)
				(type default)
			)
			(layer "F.Fab")
		)
		(fp_line
			(start -0.12065 -0.305054)
			(end -0.12065 -0.2794)
			(stroke
				(width 0.1)
				(type default)
			)
			(layer "F.Fab")
		)
		(fp_line
			(start -0.67945 0.3048)
			(end -0.67945 -0.305054)
			(stroke
				(width 0.1)
				(type default)
			)
			(layer "F.Fab")
		)
		(fp_line
			(start -0.67945 -0.305054)
			(end -0.12065 -0.305054)
			(stroke
				(width 0.1)
				(type default)
			)
			(layer "F.Fab")
		)
		(pad "1" smd circle
			(at -0.40005 0 180)
			(size 0 0)
			(layers "F.Cu" "F.Mask" "F.Paste")
			(net "USB_HUB_RREF")
		)
		(pad "2" smd circle
			(at 0.40005 0 180)
			(size 0 0)
			(layers "F.Cu" "F.Mask" "F.Paste")
			(net "GND")
		)
	)
)
